FILE_TYPE = CONNECTIVITY;
{Allegro Design Entry HDL 17.2-2016 S081 (4005846) 1/11/2022}
"PAGE_NUMBER" = 94;
0"NC";
1"M_J_CPU0_SA_CB<7:0>";
2"M_J_CPU0_SA_CA<6:0>";
3"M_J_CPU0_SB_CA<6:0>";
4"M_J_CPU0_SB_CB<7:0>";
5"M_J_CPU0_SA_DQ<31:0>";
6"M_J_CPU0_SB_DQ<31:0>";
7"M_J_CPU0_SA_DQS_DN<9:0>";
8"M_J_CPU0_SA_DQS_DP<9:0>";
9"M_J_CPU0_SB_DQS_DN<9:0>";
10"M_J_CPU0_SB_DQS_DP<9:0>";
11"GND\g";
12"GND\g";
13"P3V3_STBY\g";
14"I3C_SPD_DDRJ_CPU0_SCL";
15"I3C_SPD_DDRGL_CPU0_SCL";
16"PWRGD_CHJ_CPU0_DIMM";
17"I3C_SPD_DDRGL_CPU0_SDA";
18"PD_CHJ_CPU0_DIMM_SAA";
19"P3V3_STBY\g";
20"TP_CHJ_CPU0_DIMM_RFU_5";
21"TP_CHJ_CPU0_DIMM_RFU_6";
22"M_J_CPU0_ALERT_N";
23"M_J_CPU0_SB_DQ<23>";
24"M_J_CPU0_SA_CB<1>";
25"P12V_MEM_0\g";
26"GND\g";
27"GND\g";
28"M_J_CPU0_SB_DQS_DP<9>";
29"M_J_CPU0_SB_DQS_DN<9>";
30"M_J_CPU0_SA_DQS_DP<9>";
31"M_J_CPU0_SA_DQS_DN<9>";
32"M_J_CPU0_SA_DQS_DP<8>";
33"M_J_CPU0_SA_DQS_DN<8>";
34"M_J_CPU0_SB_DQS_DN<7>";
35"M_J_CPU0_SA_DQS_DP<7>";
36"M_J_CPU0_SB_DQS_DP<6>";
37"M_J_CPU0_SB_DQS_DN<6>";
38"M_J_CPU0_SA_DQS_DN<6>";
39"M_J_CPU0_SB_DQS_DP<5>";
40"M_J_CPU0_SB_DQS_DN<5>";
41"M_J_CPU0_SA_DQS_DP<5>";
42"M_J_CPU0_SA_DQS_DN<5>";
43"M_J_CPU0_SB_DQS_DP<4>";
44"M_J_CPU0_SB_DQS_DN<4>";
45"M_J_CPU0_SA_DQS_DP<4>";
46"M_J_CPU0_SA_DQS_DN<4>";
47"M_J_CPU0_SB_DQS_DP<3>";
48"M_J_CPU0_SB_DQS_DN<3>";
49"M_J_CPU0_SA_DQS_DP<3>";
50"M_J_CPU0_SA_DQS_DN<3>";
51"M_J_CPU0_SB_DQS_DP<2>";
52"M_J_CPU0_SB_DQS_DN<2>";
53"M_J_CPU0_SA_DQS_DP<2>";
54"M_J_CPU0_SA_DQS_DN<2>";
55"M_J_CPU0_SB_DQS_DP<1>";
56"M_J_CPU0_SB_DQS_DN<1>";
57"M_J_CPU0_SA_DQS_DP<1>";
58"M_J_CPU0_SA_DQS_DN<1>";
59"M_J_CPU0_SB_DQS_DP<0>";
60"M_J_CPU0_SB_DQS_DN<0>";
61"M_J_CPU0_SA_DQS_DP<0>";
62"M_J_CPU0_SA_DQS_DN<0>";
63"M_J_CPU0_SB_DQS_DP<7>";
64"M_J_CPU0_SB_DQS_DN<8>";
65"M_J_CPU0_SB_DQS_DP<8>";
66"M_J_CPU0_SA_DQS_DP<6>";
67"M_J_CPU0_SA_DQS_DN<7>";
68"M_J_CPU0_SA_DQ<31>";
69"M_J_CPU0_SA_DQ<30>";
70"TP_CHJ_CPU0_DIMM_RFU_0";
71"TP_CHJ_CPU0_DIMM_RFU_1";
72"TP_CHJ_CPU0_DIMM_RFU_2";
73"TP_CHJ_CPU0_DIMM_RFU_3";
74"TP_CHJ_CPU0_DIMM_RFU_4";
75"M_J_CPU0_RESET_N";
76"M_J_CPU0_SB_PAR";
77"M_J_CPU0_SA_PAR";
78"M_J_CPU0_SB_RSP<0>";
79"M_J_CPU0_SA_RSP<0>";
80"M_J_CPU0_SB_DQ<0>";
81"M_J_CPU0_SB_DQ<1>";
82"M_J_CPU0_SB_DQ<2>";
83"M_J_CPU0_SB_DQ<3>";
84"M_J_CPU0_SB_DQ<4>";
85"M_J_CPU0_SB_DQ<5>";
86"M_J_CPU0_SB_DQ<6>";
87"M_J_CPU0_SB_DQ<7>";
88"M_J_CPU0_SB_DQ<8>";
89"M_J_CPU0_SB_DQ<9>";
90"M_J_CPU0_SB_DQ<10>";
91"M_J_CPU0_SB_DQ<11>";
92"M_J_CPU0_SB_DQ<12>";
93"M_J_CPU0_SB_DQ<13>";
94"M_J_CPU0_SB_DQ<14>";
95"M_J_CPU0_SB_DQ<15>";
96"M_J_CPU0_SB_DQ<16>";
97"M_J_CPU0_SB_DQ<17>";
98"M_J_CPU0_SB_DQ<18>";
99"M_J_CPU0_SB_DQ<19>";
100"M_J_CPU0_SB_DQ<20>";
101"M_J_CPU0_SB_DQ<21>";
102"M_J_CPU0_SB_DQ<22>";
103"M_J_CPU0_SB_DQ<24>";
104"M_J_CPU0_SB_DQ<25>";
105"M_J_CPU0_SB_DQ<26>";
106"M_J_CPU0_SB_DQ<27>";
107"M_J_CPU0_SB_DQ<28>";
108"M_J_CPU0_SB_DQ<29>";
109"M_J_CPU0_SB_DQ<30>";
110"M_J_CPU0_SB_DQ<31>";
111"M_J_CPU0_SA_DQ<0>";
112"M_J_CPU0_SA_DQ<1>";
113"M_J_CPU0_SA_DQ<2>";
114"M_J_CPU0_SA_DQ<3>";
115"M_J_CPU0_SA_DQ<4>";
116"M_J_CPU0_SA_DQ<5>";
117"M_J_CPU0_SA_DQ<6>";
118"M_J_CPU0_SA_DQ<7>";
119"M_J_CPU0_SA_DQ<8>";
120"M_J_CPU0_SA_DQ<9>";
121"M_J_CPU0_SA_DQ<10>";
122"M_J_CPU0_SA_DQ<11>";
123"M_J_CPU0_SA_DQ<12>";
124"M_J_CPU0_SA_DQ<13>";
125"M_J_CPU0_SA_DQ<14>";
126"M_J_CPU0_SA_DQ<15>";
127"M_J_CPU0_SA_DQ<16>";
128"M_J_CPU0_SA_DQ<17>";
129"M_J_CPU0_SA_DQ<18>";
130"M_J_CPU0_SA_DQ<19>";
131"M_J_CPU0_SA_DQ<20>";
132"M_J_CPU0_SA_DQ<21>";
133"M_J_CPU0_SA_DQ<22>";
134"M_J_CPU0_SA_DQ<23>";
135"M_J_CPU0_SA_DQ<24>";
136"M_J_CPU0_SA_DQ<25>";
137"M_J_CPU0_SA_DQ<26>";
138"M_J_CPU0_SA_DQ<27>";
139"M_J_CPU0_SA_DQ<28>";
140"M_J_CPU0_SA_DQ<29>";
141"M_J_CPU0_SB_CS_N<1>";
142"M_J_CPU0_SA_CS_N<1>";
143"M_J_CPU0_SB_CS_N<0>";
144"M_J_CPU0_SA_CS_N<0>";
145"M_J_CPU0_CLK_DP<0>";
146"M_J_CPU0_CLK_DN<0>";
147"M_J_CPU0_SB_CB<0>";
148"M_J_CPU0_SB_CB<1>";
149"M_J_CPU0_SB_CB<2>";
150"M_J_CPU0_SB_CB<3>";
151"M_J_CPU0_SB_CB<4>";
152"M_J_CPU0_SB_CB<5>";
153"M_J_CPU0_SB_CB<6>";
154"M_J_CPU0_SA_CB<0>";
155"M_J_CPU0_SA_CB<2>";
156"M_J_CPU0_SA_CB<3>";
157"M_J_CPU0_SA_CB<5>";
158"M_J_CPU0_SA_CB<6>";
159"M_J_CPU0_SB_CA<6>";
160"M_J_CPU0_SA_CA<6>";
161"M_J_CPU0_SB_CA<5>";
162"M_J_CPU0_SA_CA<5>";
163"M_J_CPU0_SB_CA<4>";
164"M_J_CPU0_SA_CA<4>";
165"M_J_CPU0_SB_CA<3>";
166"M_J_CPU0_SA_CA<3>";
167"M_J_CPU0_SB_CA<2>";
168"M_J_CPU0_SA_CA<2>";
169"M_J_CPU0_SB_CA<1>";
170"M_J_CPU0_SA_CA<1>";
171"M_J_CPU0_SB_CA<0>";
172"M_J_CPU0_SA_CA<0>";
173"M_J_CPU0_SB_CB<7>";
174"M_J_CPU0_SA_CB<4>";
175"M_J_CPU0_SA_CB<7>";
176"GND\g";
177"PWRGD_CHGL_CPU0";
178"PD_CHJ_CPU0_DIMM_SAA";
%"TAP"
"1","(-5950,4075)","0","mstr_standard","I100";
;
CDS_LIB"mstr_standard"
BODY_TYPE"PLUMBING"
HDL_TAP"TRUE";
"B \NAC \NWC"5;
"S \NAC"
BN"6"117;
%"TAP"
"1","(-5950,4125)","0","mstr_standard","I101";
;
CDS_LIB"mstr_standard"
BODY_TYPE"PLUMBING"
HDL_TAP"TRUE";
"B \NAC \NWC"5;
"S \NAC"
BN"7"118;
%"TAP"
"1","(-5950,4275)","0","mstr_standard","I102";
;
CDS_LIB"mstr_standard"
BODY_TYPE"PLUMBING"
HDL_TAP"TRUE";
"B \NAC \NWC"5;
"S \NAC"
BN"10"121;
%"TAP"
"1","(-5950,4225)","0","mstr_standard","I103";
;
CDS_LIB"mstr_standard"
BODY_TYPE"PLUMBING"
HDL_TAP"TRUE";
"B \NAC \NWC"5;
"S \NAC"
BN"9"120;
%"TAP"
"1","(-5950,4175)","0","mstr_standard","I104";
;
CDS_LIB"mstr_standard"
BODY_TYPE"PLUMBING"
HDL_TAP"TRUE";
"B \NAC \NWC"5;
"S \NAC"
BN"8"119;
%"TAP"
"1","(-5950,4325)","0","mstr_standard","I105";
;
CDS_LIB"mstr_standard"
BODY_TYPE"PLUMBING"
HDL_TAP"TRUE";
"B \NAC \NWC"5;
"S \NAC"
BN"11"122;
%"TAP"
"1","(-5950,4375)","0","mstr_standard","I106";
;
CDS_LIB"mstr_standard"
BODY_TYPE"PLUMBING"
HDL_TAP"TRUE";
"B \NAC \NWC"5;
"S \NAC"
BN"12"123;
%"TAP"
"1","(-5950,4425)","0","mstr_standard","I107";
;
CDS_LIB"mstr_standard"
BODY_TYPE"PLUMBING"
HDL_TAP"TRUE";
"B \NAC \NWC"5;
"S \NAC"
BN"13"124;
%"TAP"
"1","(-5950,4475)","0","mstr_standard","I108";
;
CDS_LIB"mstr_standard"
BODY_TYPE"PLUMBING"
HDL_TAP"TRUE";
"B \NAC \NWC"5;
"S \NAC"
BN"14"125;
%"TAP"
"1","(-5950,4525)","0","mstr_standard","I109";
;
CDS_LIB"mstr_standard"
BODY_TYPE"PLUMBING"
HDL_TAP"TRUE";
"B \NAC \NWC"5;
"S \NAC"
BN"15"126;
%"TAP"
"1","(-5950,4625)","0","mstr_standard","I110";
;
CDS_LIB"mstr_standard"
BODY_TYPE"PLUMBING"
HDL_TAP"TRUE";
"B \NAC \NWC"5;
"S \NAC"
BN"17"128;
%"TAP"
"1","(-5950,4575)","0","mstr_standard","I111";
;
CDS_LIB"mstr_standard"
BODY_TYPE"PLUMBING"
HDL_TAP"TRUE";
"B \NAC \NWC"5;
"S \NAC"
BN"16"127;
%"TAP"
"1","(-5950,4775)","0","mstr_standard","I112";
;
CDS_LIB"mstr_standard"
BODY_TYPE"PLUMBING"
HDL_TAP"TRUE";
"B \NAC \NWC"5;
"S \NAC"
BN"20"131;
%"TAP"
"1","(-5950,4725)","0","mstr_standard","I113";
;
CDS_LIB"mstr_standard"
BODY_TYPE"PLUMBING"
HDL_TAP"TRUE";
"B \NAC \NWC"5;
"S \NAC"
BN"19"130;
%"TAP"
"1","(-5950,4675)","0","mstr_standard","I114";
;
CDS_LIB"mstr_standard"
BODY_TYPE"PLUMBING"
HDL_TAP"TRUE";
"B \NAC \NWC"5;
"S \NAC"
BN"18"129;
%"TAP"
"1","(-5950,4875)","0","mstr_standard","I115";
;
CDS_LIB"mstr_standard"
BODY_TYPE"PLUMBING"
HDL_TAP"TRUE";
"B \NAC \NWC"5;
"S \NAC"
BN"22"133;
%"TAP"
"1","(-5950,4825)","0","mstr_standard","I116";
;
CDS_LIB"mstr_standard"
BODY_TYPE"PLUMBING"
HDL_TAP"TRUE";
"B \NAC \NWC"5;
"S \NAC"
BN"21"132;
%"TAP"
"1","(-5950,5025)","0","mstr_standard","I117";
;
CDS_LIB"mstr_standard"
BODY_TYPE"PLUMBING"
HDL_TAP"TRUE";
"B \NAC \NWC"5;
"S \NAC"
BN"25"136;
%"TAP"
"1","(-5950,4975)","0","mstr_standard","I118";
;
CDS_LIB"mstr_standard"
BODY_TYPE"PLUMBING"
HDL_TAP"TRUE";
"B \NAC \NWC"5;
"S \NAC"
BN"24"135;
%"TAP"
"1","(-5950,4925)","0","mstr_standard","I119";
;
CDS_LIB"mstr_standard"
BODY_TYPE"PLUMBING"
HDL_TAP"TRUE";
"B \NAC \NWC"5;
"S \NAC"
BN"23"134;
%"TAP"
"1","(-5950,5125)","0","mstr_standard","I120";
;
CDS_LIB"mstr_standard"
BODY_TYPE"PLUMBING"
HDL_TAP"TRUE";
"B \NAC \NWC"5;
"S \NAC"
BN"27"138;
%"TAP"
"1","(-5950,5175)","0","mstr_standard","I121";
;
CDS_LIB"mstr_standard"
BODY_TYPE"PLUMBING"
HDL_TAP"TRUE";
"B \NAC \NWC"5;
"S \NAC"
BN"28"139;
%"TAP"
"1","(-5950,5075)","0","mstr_standard","I122";
;
CDS_LIB"mstr_standard"
BODY_TYPE"PLUMBING"
HDL_TAP"TRUE";
"B \NAC \NWC"5;
"S \NAC"
BN"26"137;
%"TAP"
"1","(-5950,5275)","0","mstr_standard","I123";
;
CDS_LIB"mstr_standard"
BODY_TYPE"PLUMBING"
HDL_TAP"TRUE";
"B \NAC \NWC"5;
"S \NAC"
BN"30"69;
%"TAP"
"1","(-5950,5225)","0","mstr_standard","I124";
;
CDS_LIB"mstr_standard"
BODY_TYPE"PLUMBING"
HDL_TAP"TRUE";
"B \NAC \NWC"5;
"S \NAC"
BN"29"140;
%"TAP"
"1","(-5950,5325)","0","mstr_standard","I125";
;
CDS_LIB"mstr_standard"
BODY_TYPE"PLUMBING"
HDL_TAP"TRUE";
"B \NAC \NWC"5;
"S \NAC"
BN"31"68;
%"GND"
"1","(-6350,950)","0","mstr_symbols","I128";
;
SIZE"1B"
BOM_COST"MEM"
CDS_LIB"mstr_symbols"
BODY_TYPE"PLUMBING"
VOLTAGE"0.0"
HDL_POWER"GND";
"A\NAC"11;
%"Q_RES"
"2","(-6350,1175)","0","pure_quanta","I129";
;
LOCATION"R767"
$SEC"1"
CDS_SEC"1"
WATTAGE"1/16W"
MATERIAL"CHIP"
TOLERANCE"1%"
VALUE"35.7K"
PART_NUMBER"CS33572FB01"
PACK_TYPE"0402LF"
CDS_LIB"pure_quanta";
"A"
$PN"1"178;
"B"
$PN"2"11;
%"GND"
"1","(-2050,1850)","0","mstr_symbols","I141";
;
SIZE"1B"
CDS_LIB"mstr_symbols"
BODY_TYPE"PLUMBING"
VOLTAGE"0.0"
HDL_POWER"GND";
"A\NAC"27;
%"GND"
"1","(-250,1625)","0","mstr_symbols","I142";
;
CDS_LIB"mstr_symbols"
SIZE"1B"
BODY_TYPE"PLUMBING"
VOLTAGE"0.0"
HDL_POWER"GND";
"A\NAC"26;
%"SCONN288_DDR506112002KQ"
"3","(-1150,3625)","0","pure_quanta","I177";
;
LOCATION"J68"
$SEC"3"
CDS_SEC"3"
PART_TYPE"SMLF"
MATERIAL"IO"
VALUE"SCONN288_DDR506112002KQ"
PART_NUMBER"DFHST8FS479"
CDS_LMAN_SYM_OUTLINE"-450,1800,450,-1750"
NEEDS_NO_SIZE"TRUE"
CDS_LIB"pure_quanta";
"G3"
$PN"G3"26;
"G2"
$PN"G2"26;
"G1"
$PN"G1"26;
"VSS62"
$PN"141"26;
"VSS61"
$PN"139"26;
"VSS60"
$PN"136"26;
"VSS58"
$PN"132"26;
"VSS104"
$PN"240"27;
"VSS102"
$PN"235"27;
"VSS100"
$PN"230"27;
"VIN_BULK2"
$PN"146"25;
"VIN_BULK1"
$PN"145"25;
"VIN_BULK0"
$PN"1"25;
"VSS126"
$PN"288"27;
"VSS125"
$PN"286"27;
"VSS124"
$PN"284"27;
"VSS123"
$PN"281"27;
"VSS122"
$PN"279"27;
"VSS121"
$PN"277"27;
"VSS120"
$PN"275"27;
"VSS119"
$PN"273"27;
"VSS118"
$PN"270"27;
"VSS117"
$PN"268"27;
"VSS116"
$PN"266"27;
"VSS115"
$PN"264"27;
"VSS114"
$PN"262"27;
"VSS113"
$PN"259"27;
"VSS112"
$PN"257"27;
"VSS111"
$PN"255"27;
"VSS110"
$PN"253"27;
"VSS109"
$PN"251"27;
"VSS108"
$PN"248"27;
"VSS107"
$PN"246"27;
"VSS106"
$PN"244"27;
"VSS105"
$PN"242"27;
"VSS103"
$PN"237"27;
"VSS101"
$PN"233"27;
"VSS99"
$PN"228"27;
"VSS98"
$PN"226"27;
"VSS97"
$PN"224"27;
"VSS96"
$PN"222"27;
"VSS95"
$PN"219"27;
"VSS94"
$PN"216"27;
"VSS93"
$PN"214"27;
"VSS92"
$PN"212"27;
"VSS91"
$PN"210"27;
"VSS90"
$PN"208"27;
"VSS89"
$PN"206"27;
"VSS88"
$PN"204"27;
"VSS87"
$PN"202"27;
"VSS86"
$PN"199"27;
"VSS85"
$PN"197"27;
"VSS84"
$PN"195"27;
"VSS83"
$PN"193"27;
"VSS82"
$PN"191"27;
"VSS81"
$PN"188"27;
"VSS80"
$PN"186"27;
"VSS79"
$PN"184"27;
"VSS78"
$PN"182"27;
"VSS77"
$PN"180"27;
"VSS76"
$PN"177"27;
"VSS75"
$PN"175"27;
"VSS74"
$PN"173"27;
"VSS73"
$PN"171"27;
"VSS72"
$PN"169"27;
"VSS71"
$PN"166"27;
"VSS70"
$PN"164"27;
"VSS69"
$PN"162"27;
"VSS68"
$PN"160"27;
"VSS67"
$PN"158"27;
"VSS66"
$PN"155"27;
"VSS65"
$PN"153"27;
"VSS64"
$PN"151"27;
"VSS63"
$PN"143"26;
"VSS59"
$PN"134"26;
"VSS57"
$PN"130"26;
"VSS56"
$PN"128"26;
"VSS55"
$PN"125"26;
"VSS54"
$PN"123"26;
"VSS53"
$PN"121"26;
"VSS52"
$PN"119"26;
"VSS51"
$PN"117"26;
"VSS50"
$PN"114"26;
"VSS49"
$PN"112"26;
"VSS48"
$PN"110"26;
"VSS47"
$PN"108"26;
"VSS46"
$PN"106"26;
"VSS45"
$PN"103"26;
"VSS44"
$PN"101"26;
"VSS43"
$PN"99"26;
"VSS42"
$PN"97"26;
"VSS41"
$PN"95"26;
"VSS40"
$PN"92"26;
"VSS39"
$PN"90"26;
"VSS38"
$PN"88"26;
"VSS37"
$PN"85"26;
"VSS36"
$PN"83"26;
"VSS35"
$PN"81"26;
"VSS34"
$PN"79"26;
"VSS33"
$PN"77"26;
"VSS32"
$PN"75"26;
"VSS31"
$PN"73"26;
"VSS30"
$PN"71"26;
"VSS29"
$PN"69"26;
"VSS28"
$PN"67"26;
"VSS27"
$PN"65"26;
"VSS26"
$PN"63"26;
"VSS25"
$PN"61"26;
"VSS24"
$PN"59"26;
"VSS23"
$PN"57"26;
"VSS22"
$PN"54"26;
"VSS21"
$PN"52"26;
"VSS20"
$PN"50"26;
"VSS19"
$PN"48"26;
"VSS18"
$PN"46"26;
"VSS17"
$PN"43"26;
"VSS16"
$PN"41"26;
"VSS15"
$PN"39"26;
"VSS14"
$PN"37"26;
"VSS13"
$PN"35"26;
"VSS12"
$PN"32"26;
"VSS11"
$PN"30"26;
"VSS10"
$PN"28"26;
"VSS9"
$PN"26"26;
"VSS8"
$PN"24"26;
"VSS7"
$PN"21"26;
"VSS6"
$PN"19"26;
"VSS5"
$PN"17"26;
"VSS4"
$PN"15"26;
"VSS3"
$PN"13"26;
"VSS2"
$PN"10"26;
"VSS1"
$PN"8"26;
"VSS0"
$PN"6"26;
%"Q_CAP"
"1","(-8550,3175)","2","pure_quanta","I185";
;
LOCATION"C124"
$SEC"1"
CDS_SEC"1"
MATERIAL"X7R"
TOLERANCE"10%"
VALUE"0.1UF"
VOLTAGE"25V"
PART_NUMBER"CH4104K1B00"
PACK_TYPE"0402"
BOM_COST"MEM"
CDS_LIB"pure_quanta"
ROOM"MEM_CH_A_CPU0_DIMM1";
"B"
$PN"2"12;
"A"
$PN"1"19;
%"GND"
"1","(-8550,2950)","0","mstr_symbols","I186";
;
BOM_COST"MEM"
SIZE"1B"
CDS_LIB"mstr_symbols"
BODY_TYPE"PLUMBING"
VOLTAGE"0"
ROOM"MEM_EFGH_DECOUPLING_CAPS"
HDL_POWER"GND";
"A\NAC"12;
%"Q_RES"
"1","(-8450,2075)","2","pure_quanta","I188";
;
LOCATION"R300"
$SEC"1"
CDS_SEC"1"
VALUE"0"
CDS_LIB"pure_quanta"
BOM_COST"MEM"
WATTAGE"1/16W"
MATERIAL"CHIP"
TOLERANCE"5%"
PART_NUMBER"CS00002JB38"
PACK_TYPE"0402LF"
ROOM"RST_CPU0_PLD_TO_DIMM";
"B"
$PN"2"177;
"A"
$PN"1"16;
%"Q_RES"
"2","(-8325,2225)","0","pure_quanta","I189";
;
LOCATION"R99"
$SEC"1"
CDS_SEC"1"
WATTAGE"1/16W"
MATERIAL"EMPTY"
TOLERANCE"5%"
VALUE"1K"
PACK_TYPE"0402LF"
CDS_LIB"pure_quanta"
BOM_COST"MEM"
PART_NUMBER"TMP_QCS21002JB34"
ROOM"MEM_CH_A_CPU0_DIMM1";
"A"
$PN"1"13;
"B"
$PN"2"16;
%"VCC_CORE"
"1","(-8325,2400)","0","mstr_symbols","I190";
;
HDL_POWER"P3V3_STBY"
CDS_LIB"mstr_symbols"
VOLTAGE"3.3"
ROOM"PVCCINFAON_CPU0_CTRL";
"A"13;
%"TAP"
"1","(-3175,4075)","0","mstr_standard","I196";
;
CDS_LIB"mstr_standard"
BODY_TYPE"PLUMBING"
HDL_TAP"TRUE";
"B \NAC \NWC"7;
"S \NAC"
BN"8"33;
%"TAP"
"1","(-3175,4175)","0","mstr_standard","I197";
;
CDS_LIB"mstr_standard"
BODY_TYPE"PLUMBING"
HDL_TAP"TRUE";
"B \NAC \NWC"7;
"S \NAC"
BN"9"31;
%"TAP"
"1","(-3375,4225)","0","mstr_standard","I198";
;
CDS_LIB"mstr_standard"
BODY_TYPE"PLUMBING"
HDL_TAP"TRUE";
"B \NAC \NWC"8;
"S \NAC"
BN"9"30;
%"TAP"
"1","(-3375,4125)","0","mstr_standard","I199";
;
CDS_LIB"mstr_standard"
BODY_TYPE"PLUMBING"
HDL_TAP"TRUE";
"B \NAC \NWC"8;
"S \NAC"
BN"8"32;
%"TAP"
"1","(-3175,3975)","0","mstr_standard","I200";
;
CDS_LIB"mstr_standard"
BODY_TYPE"PLUMBING"
HDL_TAP"TRUE";
"B \NAC \NWC"7;
"S \NAC"
BN"7"67;
%"TAP"
"1","(-3175,3875)","0","mstr_standard","I201";
;
CDS_LIB"mstr_standard"
BODY_TYPE"PLUMBING"
HDL_TAP"TRUE";
"B \NAC \NWC"7;
"S \NAC"
BN"6"38;
%"TAP"
"1","(-3175,3775)","0","mstr_standard","I202";
;
CDS_LIB"mstr_standard"
BODY_TYPE"PLUMBING"
HDL_TAP"TRUE";
"B \NAC \NWC"7;
"S \NAC"
BN"5"42;
%"TAP"
"1","(-3175,3675)","0","mstr_standard","I203";
;
CDS_LIB"mstr_standard"
BODY_TYPE"PLUMBING"
HDL_TAP"TRUE";
"B \NAC \NWC"7;
"S \NAC"
BN"4"46;
%"TAP"
"1","(-3175,3575)","0","mstr_standard","I204";
;
CDS_LIB"mstr_standard"
BODY_TYPE"PLUMBING"
HDL_TAP"TRUE";
"B \NAC \NWC"7;
"S \NAC"
BN"3"50;
%"TAP"
"1","(-3175,3475)","0","mstr_standard","I205";
;
CDS_LIB"mstr_standard"
BODY_TYPE"PLUMBING"
HDL_TAP"TRUE";
"B \NAC \NWC"7;
"S \NAC"
BN"2"54;
%"TAP"
"1","(-3175,3375)","0","mstr_standard","I206";
;
CDS_LIB"mstr_standard"
BODY_TYPE"PLUMBING"
HDL_TAP"TRUE";
"B \NAC \NWC"7;
"S \NAC"
BN"1"58;
%"TAP"
"1","(-3175,3275)","0","mstr_standard","I207";
;
CDS_LIB"mstr_standard"
BODY_TYPE"PLUMBING"
HDL_TAP"TRUE";
"B \NAC \NWC"7;
"S \NAC"
BN"0"62;
%"TAP"
"1","(-3175,3125)","0","mstr_standard","I208";
;
CDS_LIB"mstr_standard"
BODY_TYPE"PLUMBING"
HDL_TAP"TRUE";
"B \NAC \NWC"9;
"S \NAC"
BN"9"29;
%"TAP"
"1","(-3375,4025)","0","mstr_standard","I209";
;
CDS_LIB"mstr_standard"
BODY_TYPE"PLUMBING"
HDL_TAP"TRUE";
"B \NAC \NWC"8;
"S \NAC"
BN"7"35;
%"TAP"
"1","(-3375,3925)","0","mstr_standard","I210";
;
CDS_LIB"mstr_standard"
BODY_TYPE"PLUMBING"
HDL_TAP"TRUE";
"B \NAC \NWC"8;
"S \NAC"
BN"6"66;
%"TAP"
"1","(-3375,3825)","0","mstr_standard","I211";
;
CDS_LIB"mstr_standard"
BODY_TYPE"PLUMBING"
HDL_TAP"TRUE";
"B \NAC \NWC"8;
"S \NAC"
BN"5"41;
%"TAP"
"1","(-3375,3725)","0","mstr_standard","I212";
;
CDS_LIB"mstr_standard"
BODY_TYPE"PLUMBING"
HDL_TAP"TRUE";
"B \NAC \NWC"8;
"S \NAC"
BN"4"45;
%"TAP"
"1","(-3375,3625)","0","mstr_standard","I213";
;
CDS_LIB"mstr_standard"
BODY_TYPE"PLUMBING"
HDL_TAP"TRUE";
"B \NAC \NWC"8;
"S \NAC"
BN"3"49;
%"TAP"
"1","(-3375,3525)","0","mstr_standard","I214";
;
CDS_LIB"mstr_standard"
BODY_TYPE"PLUMBING"
HDL_TAP"TRUE";
"B \NAC \NWC"8;
"S \NAC"
BN"2"53;
%"TAP"
"1","(-3375,3425)","0","mstr_standard","I215";
;
CDS_LIB"mstr_standard"
BODY_TYPE"PLUMBING"
HDL_TAP"TRUE";
"B \NAC \NWC"8;
"S \NAC"
BN"1"57;
%"TAP"
"1","(-3375,3325)","0","mstr_standard","I216";
;
CDS_LIB"mstr_standard"
BODY_TYPE"PLUMBING"
HDL_TAP"TRUE";
"B \NAC \NWC"8;
"S \NAC"
BN"0"61;
%"TAP"
"1","(-3375,3175)","0","mstr_standard","I217";
;
CDS_LIB"mstr_standard"
BODY_TYPE"PLUMBING"
HDL_TAP"TRUE";
"B \NAC \NWC"10;
"S \NAC"
BN"9"28;
%"TAP"
"1","(-3375,3075)","0","mstr_standard","I218";
;
CDS_LIB"mstr_standard"
BODY_TYPE"PLUMBING"
HDL_TAP"TRUE";
"B \NAC \NWC"10;
"S \NAC"
BN"8"65;
%"TAP"
"1","(-3175,2925)","0","mstr_standard","I219";
;
CDS_LIB"mstr_standard"
BODY_TYPE"PLUMBING"
HDL_TAP"TRUE";
"B \NAC \NWC"9;
"S \NAC"
BN"7"34;
%"SCONN288_DDR506112002KQ"
"1","(-6800,3575)","0","pure_quanta","I22";
;
LOCATION"J68"
$SEC"1"
CDS_SEC"1"
MATERIAL"IO"
PART_NUMBER"DFHST8FS479"
VALUE"SCONN288_DDR506112002KQ"
PART_TYPE"SMLF"
CDS_LMAN_SYM_OUTLINE"-450,1900,450,-1850"
NEEDS_NO_SIZE"TRUE"
CDS_LIB"pure_quanta";
"PWR_GOOD||FAIL_N"
$PN"147"16;
"DQ31_A"
$PN"194"68;
"CB7_A"
$PN"205"175;
"CB4_A"
$PN"58"174;
"CB1_A"
$PN"53"24;
"CB7_B"
$PN"236"173;
"ALERT_N \B"
$PN"62"22;
"CA0_A"
$PN"66"172;
"CA0_B"
$PN"76"171;
"CA1_A"
$PN"211"170;
"CA1_B"
$PN"221"169;
"CA2_A"
$PN"68"168;
"CA2_B"
$PN"78"167;
"CA3_A"
$PN"213"166;
"CA3_B"
$PN"223"165;
"CA4_A"
$PN"70"164;
"CA4_B"
$PN"80"163;
"CA5_A"
$PN"215"162;
"CA5_B"
$PN"225"161;
"CA6_A"
$PN"72"160;
"CA6_B"
$PN"82"159;
"CB6_A"
$PN"203"158;
"CB5_A"
$PN"60"157;
"CB3_A"
$PN"198"156;
"CB2_A"
$PN"196"155;
"CB0_A"
$PN"51"154;
"CB6_B"
$PN"234"153;
"CB5_B"
$PN"91"152;
"CB4_B"
$PN"89"151;
"CB3_B"
$PN"243"150;
"CB2_B"
$PN"241"149;
"CB1_B"
$PN"98"148;
"CB0_B"
$PN"96"147;
"CK_C \B"
$PN"218"146;
"CK_T"
$PN"217"145;
"CS0_A_N"
$PN"64"144;
"CS0_B_N"
$PN"84"143;
"CS1_A_N"
$PN"209"142;
"CS1_B_N"
$PN"229"141;
"DQ30_A"
$PN"192"69;
"DQ29_A"
$PN"49"140;
"DQ28_A"
$PN"47"139;
"DQ27_A"
$PN"187"138;
"DQ26_A"
$PN"185"137;
"DQ25_A"
$PN"42"136;
"DQ24_A"
$PN"40"135;
"DQ23_A"
$PN"183"134;
"DQ22_A"
$PN"181"133;
"DQ21_A"
$PN"38"132;
"DQ20_A"
$PN"36"131;
"DQ19_A"
$PN"176"130;
"DQ18_A"
$PN"174"129;
"DQ17_A"
$PN"31"128;
"DQ16_A"
$PN"29"127;
"DQ15_A"
$PN"172"126;
"DQ14_A"
$PN"170"125;
"DQ13_A"
$PN"27"124;
"DQ12_A"
$PN"25"123;
"DQ11_A"
$PN"165"122;
"DQ10_A"
$PN"163"121;
"DQ9_A"
$PN"20"120;
"DQ8_A"
$PN"18"119;
"DQ7_A"
$PN"161"118;
"DQ6_A"
$PN"159"117;
"DQ5_A"
$PN"16"116;
"DQ4_A"
$PN"14"115;
"DQ3_A"
$PN"154"114;
"DQ2_A"
$PN"152"113;
"DQ1_A"
$PN"9"112;
"DQ0_A"
$PN"7"111;
"DQ31_B"
$PN"287"110;
"DQ30_B"
$PN"285"109;
"DQ29_B"
$PN"142"108;
"DQ28_B"
$PN"140"107;
"DQ27_B"
$PN"280"106;
"DQ26_B"
$PN"278"105;
"DQ25_B"
$PN"135"104;
"DQ24_B"
$PN"133"103;
"DQ23_B"
$PN"276"23;
"DQ22_B"
$PN"274"102;
"DQ21_B"
$PN"131"101;
"DQ20_B"
$PN"129"100;
"DQ19_B"
$PN"269"99;
"DQ18_B"
$PN"267"98;
"DQ17_B"
$PN"124"97;
"DQ16_B"
$PN"122"96;
"DQ15_B"
$PN"265"95;
"DQ14_B"
$PN"263"94;
"DQ13_B"
$PN"120"93;
"DQ12_B"
$PN"118"92;
"DQ11_B"
$PN"258"91;
"DQ10_B"
$PN"256"90;
"DQ9_B"
$PN"113"89;
"DQ8_B"
$PN"111"88;
"DQ7_B"
$PN"254"87;
"DQ6_B"
$PN"252"86;
"DQ5_B"
$PN"109"85;
"DQ4_B"
$PN"107"84;
"DQ3_B"
$PN"247"83;
"DQ2_B"
$PN"245"82;
"DQ1_B"
$PN"102"81;
"DQ0_B"
$PN"100"80;
"HAS"
$PN"148"18;
"HSCL"
$PN"4"14;
"HSDA"
$PN"5"17;
"LBD||RSP_A_N"
$PN"86"79;
"LBS||RSP_B_N"
$PN"87"78;
"PAR_A"
$PN"74"77;
"PAR_B"
$PN"227"76;
"RESET_N \B"
$PN"207"75;
"RFU6"
$PN"232"21;
"RFU5"
$PN"231"20;
"RFU4"
$PN"220"74;
"RFU3"
$PN"150"73;
"RFU2"
$PN"149"72;
"RFU1"
$PN"144"71;
"RFU0"
$PN"2"70;
"VIN_MGMT"
$PN"3"19;
%"TAP"
"1","(-3175,3025)","0","mstr_standard","I220";
;
CDS_LIB"mstr_standard"
BODY_TYPE"PLUMBING"
HDL_TAP"TRUE";
"B \NAC \NWC"9;
"S \NAC"
BN"8"64;
%"TAP"
"1","(-3175,2825)","0","mstr_standard","I221";
;
CDS_LIB"mstr_standard"
BODY_TYPE"PLUMBING"
HDL_TAP"TRUE";
"B \NAC \NWC"9;
"S \NAC"
BN"6"37;
%"TAP"
"1","(-3175,2625)","0","mstr_standard","I222";
;
CDS_LIB"mstr_standard"
BODY_TYPE"PLUMBING"
HDL_TAP"TRUE";
"B \NAC \NWC"9;
"S \NAC"
BN"4"44;
%"TAP"
"1","(-3175,2725)","0","mstr_standard","I223";
;
CDS_LIB"mstr_standard"
BODY_TYPE"PLUMBING"
HDL_TAP"TRUE";
"B \NAC \NWC"9;
"S \NAC"
BN"5"40;
%"TAP"
"1","(-3175,2525)","0","mstr_standard","I224";
;
CDS_LIB"mstr_standard"
BODY_TYPE"PLUMBING"
HDL_TAP"TRUE";
"B \NAC \NWC"9;
"S \NAC"
BN"3"48;
%"TAP"
"1","(-3175,2325)","0","mstr_standard","I225";
;
CDS_LIB"mstr_standard"
BODY_TYPE"PLUMBING"
HDL_TAP"TRUE";
"B \NAC \NWC"9;
"S \NAC"
BN"1"56;
%"TAP"
"1","(-3175,2425)","0","mstr_standard","I226";
;
CDS_LIB"mstr_standard"
BODY_TYPE"PLUMBING"
HDL_TAP"TRUE";
"B \NAC \NWC"9;
"S \NAC"
BN"2"52;
%"TAP"
"1","(-3175,2225)","0","mstr_standard","I227";
;
CDS_LIB"mstr_standard"
BODY_TYPE"PLUMBING"
HDL_TAP"TRUE";
"B \NAC \NWC"9;
"S \NAC"
BN"0"60;
%"TAP"
"1","(-3375,2975)","0","mstr_standard","I228";
;
CDS_LIB"mstr_standard"
BODY_TYPE"PLUMBING"
HDL_TAP"TRUE";
"B \NAC \NWC"10;
"S \NAC"
BN"7"63;
%"TAP"
"1","(-3375,2875)","0","mstr_standard","I229";
;
CDS_LIB"mstr_standard"
BODY_TYPE"PLUMBING"
HDL_TAP"TRUE";
"B \NAC \NWC"10;
"S \NAC"
BN"6"36;
%"TAP"
"1","(-7650,3125)","2","mstr_standard","I23";
;
CDS_LIB"mstr_standard"
BODY_TYPE"PLUMBING"
HDL_TAP"TRUE";
"B \NAC \NWC"4;
"S \NAC"
BN"0"147;
%"TAP"
"1","(-3375,2675)","0","mstr_standard","I230";
;
CDS_LIB"mstr_standard"
BODY_TYPE"PLUMBING"
HDL_TAP"TRUE";
"B \NAC \NWC"10;
"S \NAC"
BN"4"43;
%"TAP"
"1","(-3375,2775)","0","mstr_standard","I231";
;
CDS_LIB"mstr_standard"
BODY_TYPE"PLUMBING"
HDL_TAP"TRUE";
"B \NAC \NWC"10;
"S \NAC"
BN"5"39;
%"TAP"
"1","(-3375,2575)","0","mstr_standard","I232";
;
CDS_LIB"mstr_standard"
BODY_TYPE"PLUMBING"
HDL_TAP"TRUE";
"B \NAC \NWC"10;
"S \NAC"
BN"3"47;
%"TAP"
"1","(-3375,2475)","0","mstr_standard","I233";
;
CDS_LIB"mstr_standard"
BODY_TYPE"PLUMBING"
HDL_TAP"TRUE";
"B \NAC \NWC"10;
"S \NAC"
BN"2"51;
%"TAP"
"1","(-3375,2375)","0","mstr_standard","I234";
;
CDS_LIB"mstr_standard"
BODY_TYPE"PLUMBING"
HDL_TAP"TRUE";
"B \NAC \NWC"10;
"S \NAC"
BN"1"55;
%"TAP"
"1","(-3375,2275)","0","mstr_standard","I235";
;
CDS_LIB"mstr_standard"
BODY_TYPE"PLUMBING"
HDL_TAP"TRUE";
"B \NAC \NWC"10;
"S \NAC"
BN"0"59;
%"SCONN288_DDR506112002KQ"
"2","(-4325,3225)","0","pure_quanta","I236";
;
LOCATION"J68"
$SEC"2"
CDS_SEC"2"
MATERIAL"IO"
PART_NUMBER"DFHST8FS479"
VALUE"SCONN288_DDR506112002KQ"
PART_TYPE"SMLF"
CDS_LMAN_SYM_OUTLINE"-600,1150,600,-1150"
NEEDS_NO_SIZE"TRUE"
CDS_LIB"pure_quanta";
"DQS7_A_C||TDQS7_A_C \B"
$PN"178"67;
"DQS6_A_T||TDQS6_A_T"
$PN"168"66;
"DQS8_B_T||TDQS8_B_T"
$PN"283"65;
"DQS8_B_C||TDQS8_B_C \B"
$PN"282"64;
"DQS7_B_T||TDQS7_B_T"
$PN"272"63;
"DQS0_A_C \B"
$PN"12"62;
"DQS0_A_T"
$PN"11"61;
"DQS0_B_C \B"
$PN"105"60;
"DQS0_B_T"
$PN"104"59;
"DQS1_A_C \B"
$PN"23"58;
"DQS1_A_T"
$PN"22"57;
"DQS1_B_C \B"
$PN"116"56;
"DQS1_B_T"
$PN"115"55;
"DQS2_A_C \B"
$PN"34"54;
"DQS2_A_T"
$PN"33"53;
"DQS2_B_C \B"
$PN"127"52;
"DQS2_B_T"
$PN"126"51;
"DQS3_A_C \B"
$PN"45"50;
"DQS3_A_T"
$PN"44"49;
"DQS3_B_C \B"
$PN"138"48;
"DQS3_B_T"
$PN"137"47;
"DQS4_A_C \B"
$PN"56"46;
"DQS4_A_T"
$PN"55"45;
"DQS4_B_C \B"
$PN"238"44;
"DQS4_B_T"
$PN"239"43;
"DQS5_A_C||TDQS5_A_C||DQS5_A_T||TDQS5_A_T \B"
$PN"156"42;
"DQS5_A_T||TDQS5_A_T"
$PN"157"41;
"DQS5_B_C||TDQS5_B_C \B"
$PN"249"40;
"DQS5_B_T||TDQS5_B_T"
$PN"250"39;
"DQS6_A_C||TDQS6_A_C||DQS6_A_T||TDQS6_A_T \B"
$PN"167"38;
"DQS6_B_C||TDQS6_B_C \B"
$PN"260"37;
"DQS6_B_T||TDQS6_B_T"
$PN"261"36;
"DQS7_A_T||TDQS7_A_T"
$PN"179"35;
"DQS7_B_C||TDQS7_B_C \B"
$PN"271"34;
"DQS8_A_C||TDQS8_A_C \B"
$PN"189"33;
"DQS8_A_T||TDQS8_A_T"
$PN"190"32;
"DQS9_A_C||TDQS9_A_C \B"
$PN"200"31;
"DQS9_A_T||TDQS9_A_T"
$PN"201"30;
"DQS9_B_C||TDQS9_B_C \B"
$PN"94"29;
"DQS9_B_T||TDQS9_B_T||DBI4_B_N"
$PN"93"28;
%"GND"
"1","(-2750,5475)","0","pure_quanta_power","I237";
;
CDS_LIB"pure_quanta_power"
BOM_COST"MEM"
SIZE"1B"
ROOM"MEM_EFGH_DECOUPLING_CAPS"
HDL_POWER"GND";
"A<SIZE-1..0>\NAC"176;
%"Q_CAP"
"1","(-2750,5825)","2","pure_quanta","I238";
;
LOCATION"C165"
$SEC"1"
CDS_SEC"1"
MATERIAL"X6S"
TOLERANCE"10%"
VALUE"10UF"
PACK_TYPE"C0805"
VOLTAGE"25V"
PART_NUMBER"CH6104KEA00"
BOM_COST"MEM"
CDS_LIB"pure_quanta"
ROOM"MEM_CH_A_CPU0_DIMM1";
"B"
$PN"2"176;
"A"
$PN"1"25;
%"Q_CAP"
"1","(-2175,5825)","2","pure_quanta","I239";
;
LOCATION"C166"
$SEC"1"
CDS_SEC"1"
MATERIAL"X6S"
TOLERANCE"10%"
VALUE"10UF"
VOLTAGE"25V"
PACK_TYPE"C0805"
PART_NUMBER"CH6104KEA00"
BOM_COST"MEM"
CDS_LIB"pure_quanta"
ROOM"MEM_CH_A_CPU0_DIMM1";
"B"
$PN"2"176;
"A"
$PN"1"25;
%"TAP"
"1","(-7650,3175)","2","mstr_standard","I24";
;
CDS_LIB"mstr_standard"
BODY_TYPE"PLUMBING"
HDL_TAP"TRUE";
"B \NAC \NWC"4;
"S \NAC"
BN"1"148;
%"UNIVERSAL_POWER"
"1","(-2750,6150)","0","pure_quanta_power","I240";
;
HDL_POWER"P12V_MEM_0"
BOM_COST"VR_SYSTEM"
CDS_LIB"pure_quanta_power";
"A"25;
%"Q_RES"
"1","(-7700,2625)","0","pure_quanta","I242";
;
$LOCATION"R1577"
CDS_LOCATION"R1577"
$SEC"1"
CDS_SEC"1"
VALUE"49.9"
CDS_LIB"pure_quanta"
MATERIAL"CHIP"
PACK_TYPE"0402LF"
WATTAGE"1/16W"
TOLERANCE"1%"
PART_NUMBER"CS04992FB07";
"B"
$PN"2"14;
"A"
$PN"1"15;
%"TAP"
"1","(-7650,3225)","2","mstr_standard","I25";
;
CDS_LIB"mstr_standard"
BODY_TYPE"PLUMBING"
HDL_TAP"TRUE";
"B \NAC \NWC"4;
"S \NAC"
BN"2"149;
%"TAP"
"1","(-7650,3275)","2","mstr_standard","I26";
;
CDS_LIB"mstr_standard"
BODY_TYPE"PLUMBING"
HDL_TAP"TRUE";
"B \NAC \NWC"4;
"S \NAC"
BN"3"150;
%"TAP"
"1","(-7650,3325)","2","mstr_standard","I27";
;
CDS_LIB"mstr_standard"
BODY_TYPE"PLUMBING"
HDL_TAP"TRUE";
"B \NAC \NWC"4;
"S \NAC"
BN"4"151;
%"TAP"
"1","(-7650,3375)","2","mstr_standard","I28";
;
CDS_LIB"mstr_standard"
BODY_TYPE"PLUMBING"
HDL_TAP"TRUE";
"B \NAC \NWC"4;
"S \NAC"
BN"5"152;
%"TAP"
"1","(-7650,3425)","2","mstr_standard","I29";
;
CDS_LIB"mstr_standard"
BODY_TYPE"PLUMBING"
HDL_TAP"TRUE";
"B \NAC \NWC"4;
"S \NAC"
BN"6"153;
%"TAP"
"1","(-7650,3475)","2","mstr_standard","I30";
;
CDS_LIB"mstr_standard"
BODY_TYPE"PLUMBING"
HDL_TAP"TRUE";
"B \NAC \NWC"4;
"S \NAC"
BN"7"173;
%"TAP"
"1","(-7650,3575)","2","mstr_standard","I31";
;
CDS_LIB"mstr_standard"
BODY_TYPE"PLUMBING"
HDL_TAP"TRUE";
"B \NAC \NWC"1;
"S \NAC"
BN"0"154;
%"TAP"
"1","(-7650,3625)","2","mstr_standard","I32";
;
CDS_LIB"mstr_standard"
BODY_TYPE"PLUMBING"
HDL_TAP"TRUE";
"B \NAC \NWC"1;
"S \NAC"
BN"1"24;
%"TAP"
"1","(-7650,3725)","2","mstr_standard","I33";
;
CDS_LIB"mstr_standard"
BODY_TYPE"PLUMBING"
HDL_TAP"TRUE";
"B \NAC \NWC"1;
"S \NAC"
BN"3"156;
%"TAP"
"1","(-7650,3675)","2","mstr_standard","I34";
;
CDS_LIB"mstr_standard"
BODY_TYPE"PLUMBING"
HDL_TAP"TRUE";
"B \NAC \NWC"1;
"S \NAC"
BN"2"155;
%"TAP"
"1","(-5950,2125)","0","mstr_standard","I35";
;
CDS_LIB"mstr_standard"
BODY_TYPE"PLUMBING"
HDL_TAP"TRUE";
"B \NAC \NWC"6;
"S \NAC"
BN"0"80;
%"TAP"
"1","(-5950,2225)","0","mstr_standard","I36";
;
CDS_LIB"mstr_standard"
BODY_TYPE"PLUMBING"
HDL_TAP"TRUE";
"B \NAC \NWC"6;
"S \NAC"
BN"2"82;
%"TAP"
"1","(-5950,2175)","0","mstr_standard","I37";
;
CDS_LIB"mstr_standard"
BODY_TYPE"PLUMBING"
HDL_TAP"TRUE";
"B \NAC \NWC"6;
"S \NAC"
BN"1"81;
%"TAP"
"1","(-5950,2325)","0","mstr_standard","I38";
;
CDS_LIB"mstr_standard"
BODY_TYPE"PLUMBING"
HDL_TAP"TRUE";
"B \NAC \NWC"6;
"S \NAC"
BN"4"84;
%"TAP"
"1","(-5950,2275)","0","mstr_standard","I39";
;
CDS_LIB"mstr_standard"
BODY_TYPE"PLUMBING"
HDL_TAP"TRUE";
"B \NAC \NWC"6;
"S \NAC"
BN"3"83;
%"TAP"
"1","(-5950,2375)","0","mstr_standard","I40";
;
CDS_LIB"mstr_standard"
BODY_TYPE"PLUMBING"
HDL_TAP"TRUE";
"B \NAC \NWC"6;
"S \NAC"
BN"5"85;
%"TAP"
"1","(-5950,2425)","0","mstr_standard","I41";
;
CDS_LIB"mstr_standard"
BODY_TYPE"PLUMBING"
HDL_TAP"TRUE";
"B \NAC \NWC"6;
"S \NAC"
BN"6"86;
%"TAP"
"1","(-5950,2475)","0","mstr_standard","I42";
;
CDS_LIB"mstr_standard"
BODY_TYPE"PLUMBING"
HDL_TAP"TRUE";
"B \NAC \NWC"6;
"S \NAC"
BN"7"87;
%"TAP"
"1","(-5950,2575)","0","mstr_standard","I43";
;
CDS_LIB"mstr_standard"
BODY_TYPE"PLUMBING"
HDL_TAP"TRUE";
"B \NAC \NWC"6;
"S \NAC"
BN"9"89;
%"TAP"
"1","(-5950,2525)","0","mstr_standard","I44";
;
CDS_LIB"mstr_standard"
BODY_TYPE"PLUMBING"
HDL_TAP"TRUE";
"B \NAC \NWC"6;
"S \NAC"
BN"8"88;
%"TAP"
"1","(-5950,2625)","0","mstr_standard","I45";
;
CDS_LIB"mstr_standard"
BODY_TYPE"PLUMBING"
HDL_TAP"TRUE";
"B \NAC \NWC"6;
"S \NAC"
BN"10"90;
%"TAP"
"1","(-5950,2725)","0","mstr_standard","I46";
;
CDS_LIB"mstr_standard"
BODY_TYPE"PLUMBING"
HDL_TAP"TRUE";
"B \NAC \NWC"6;
"S \NAC"
BN"12"92;
%"TAP"
"1","(-5950,2675)","0","mstr_standard","I47";
;
CDS_LIB"mstr_standard"
BODY_TYPE"PLUMBING"
HDL_TAP"TRUE";
"B \NAC \NWC"6;
"S \NAC"
BN"11"91;
%"TAP"
"1","(-5950,2825)","0","mstr_standard","I48";
;
CDS_LIB"mstr_standard"
BODY_TYPE"PLUMBING"
HDL_TAP"TRUE";
"B \NAC \NWC"6;
"S \NAC"
BN"14"94;
%"TAP"
"1","(-5950,2775)","0","mstr_standard","I49";
;
CDS_LIB"mstr_standard"
BODY_TYPE"PLUMBING"
HDL_TAP"TRUE";
"B \NAC \NWC"6;
"S \NAC"
BN"13"93;
%"TAP"
"1","(-5950,2875)","0","mstr_standard","I50";
;
CDS_LIB"mstr_standard"
BODY_TYPE"PLUMBING"
HDL_TAP"TRUE";
"B \NAC \NWC"6;
"S \NAC"
BN"15"95;
%"TAP"
"1","(-5950,2975)","0","mstr_standard","I51";
;
CDS_LIB"mstr_standard"
BODY_TYPE"PLUMBING"
HDL_TAP"TRUE";
"B \NAC \NWC"6;
"S \NAC"
BN"17"97;
%"TAP"
"1","(-5950,2925)","0","mstr_standard","I52";
;
CDS_LIB"mstr_standard"
BODY_TYPE"PLUMBING"
HDL_TAP"TRUE";
"B \NAC \NWC"6;
"S \NAC"
BN"16"96;
%"TAP"
"1","(-5950,3125)","0","mstr_standard","I53";
;
CDS_LIB"mstr_standard"
BODY_TYPE"PLUMBING"
HDL_TAP"TRUE";
"B \NAC \NWC"6;
"S \NAC"
BN"20"100;
%"TAP"
"1","(-5950,3075)","0","mstr_standard","I54";
;
CDS_LIB"mstr_standard"
BODY_TYPE"PLUMBING"
HDL_TAP"TRUE";
"B \NAC \NWC"6;
"S \NAC"
BN"19"99;
%"TAP"
"1","(-5950,3025)","0","mstr_standard","I55";
;
CDS_LIB"mstr_standard"
BODY_TYPE"PLUMBING"
HDL_TAP"TRUE";
"B \NAC \NWC"6;
"S \NAC"
BN"18"98;
%"TAP"
"1","(-5950,3175)","0","mstr_standard","I56";
;
CDS_LIB"mstr_standard"
BODY_TYPE"PLUMBING"
HDL_TAP"TRUE";
"B \NAC \NWC"6;
"S \NAC"
BN"21"101;
%"TAP"
"1","(-5950,3225)","0","mstr_standard","I57";
;
CDS_LIB"mstr_standard"
BODY_TYPE"PLUMBING"
HDL_TAP"TRUE";
"B \NAC \NWC"6;
"S \NAC"
BN"22"102;
%"TAP"
"1","(-5950,3375)","0","mstr_standard","I58";
;
CDS_LIB"mstr_standard"
BODY_TYPE"PLUMBING"
HDL_TAP"TRUE";
"B \NAC \NWC"6;
"S \NAC"
BN"25"104;
%"TAP"
"1","(-5950,3325)","0","mstr_standard","I59";
;
CDS_LIB"mstr_standard"
BODY_TYPE"PLUMBING"
HDL_TAP"TRUE";
"B \NAC \NWC"6;
"S \NAC"
BN"24"103;
%"TAP"
"1","(-5950,3275)","0","mstr_standard","I60";
;
CDS_LIB"mstr_standard"
BODY_TYPE"PLUMBING"
HDL_TAP"TRUE";
"B \NAC \NWC"6;
"S \NAC"
BN"23"23;
%"TAP"
"1","(-5950,3425)","0","mstr_standard","I61";
;
CDS_LIB"mstr_standard"
BODY_TYPE"PLUMBING"
HDL_TAP"TRUE";
"B \NAC \NWC"6;
"S \NAC"
BN"26"105;
%"TAP"
"1","(-5950,3475)","0","mstr_standard","I62";
;
CDS_LIB"mstr_standard"
BODY_TYPE"PLUMBING"
HDL_TAP"TRUE";
"B \NAC \NWC"6;
"S \NAC"
BN"27"106;
%"TAP"
"1","(-5950,3625)","0","mstr_standard","I63";
;
CDS_LIB"mstr_standard"
BODY_TYPE"PLUMBING"
HDL_TAP"TRUE";
"B \NAC \NWC"6;
"S \NAC"
BN"30"109;
%"TAP"
"1","(-5950,3575)","0","mstr_standard","I64";
;
CDS_LIB"mstr_standard"
BODY_TYPE"PLUMBING"
HDL_TAP"TRUE";
"B \NAC \NWC"6;
"S \NAC"
BN"29"108;
%"TAP"
"1","(-5950,3525)","0","mstr_standard","I65";
;
CDS_LIB"mstr_standard"
BODY_TYPE"PLUMBING"
HDL_TAP"TRUE";
"B \NAC \NWC"6;
"S \NAC"
BN"28"107;
%"TAP"
"1","(-5950,3675)","0","mstr_standard","I66";
;
CDS_LIB"mstr_standard"
BODY_TYPE"PLUMBING"
HDL_TAP"TRUE";
"B \NAC \NWC"6;
"S \NAC"
BN"31"110;
%"TAP"
"1","(-7650,3775)","2","mstr_standard","I76";
;
CDS_LIB"mstr_standard"
BODY_TYPE"PLUMBING"
HDL_TAP"TRUE";
"B \NAC \NWC"1;
"S \NAC"
BN"4"174;
%"TAP"
"1","(-7650,3825)","2","mstr_standard","I77";
;
CDS_LIB"mstr_standard"
BODY_TYPE"PLUMBING"
HDL_TAP"TRUE";
"B \NAC \NWC"1;
"S \NAC"
BN"5"157;
%"TAP"
"1","(-7650,3875)","2","mstr_standard","I78";
;
CDS_LIB"mstr_standard"
BODY_TYPE"PLUMBING"
HDL_TAP"TRUE";
"B \NAC \NWC"1;
"S \NAC"
BN"6"158;
%"TAP"
"1","(-7650,3925)","2","mstr_standard","I79";
;
CDS_LIB"mstr_standard"
BODY_TYPE"PLUMBING"
HDL_TAP"TRUE";
"B \NAC \NWC"1;
"S \NAC"
BN"7"175;
%"TAP"
"1","(-7650,4625)","2","mstr_standard","I80";
;
CDS_LIB"mstr_standard"
BODY_TYPE"PLUMBING"
HDL_TAP"TRUE";
"B \NAC \NWC"3;
"S \NAC"
BN"0"171;
%"TAP"
"1","(-7650,4675)","2","mstr_standard","I81";
;
CDS_LIB"mstr_standard"
BODY_TYPE"PLUMBING"
HDL_TAP"TRUE";
"B \NAC \NWC"3;
"S \NAC"
BN"1"169;
%"TAP"
"1","(-7650,4725)","2","mstr_standard","I82";
;
CDS_LIB"mstr_standard"
BODY_TYPE"PLUMBING"
HDL_TAP"TRUE";
"B \NAC \NWC"3;
"S \NAC"
BN"2"167;
%"TAP"
"1","(-7650,4775)","2","mstr_standard","I83";
;
CDS_LIB"mstr_standard"
BODY_TYPE"PLUMBING"
HDL_TAP"TRUE";
"B \NAC \NWC"3;
"S \NAC"
BN"3"165;
%"TAP"
"1","(-7650,4825)","2","mstr_standard","I84";
;
CDS_LIB"mstr_standard"
BODY_TYPE"PLUMBING"
HDL_TAP"TRUE";
"B \NAC \NWC"3;
"S \NAC"
BN"4"163;
%"TAP"
"1","(-7650,4875)","2","mstr_standard","I85";
;
CDS_LIB"mstr_standard"
BODY_TYPE"PLUMBING"
HDL_TAP"TRUE";
"B \NAC \NWC"3;
"S \NAC"
BN"5"161;
%"TAP"
"1","(-7650,4925)","2","mstr_standard","I86";
;
CDS_LIB"mstr_standard"
BODY_TYPE"PLUMBING"
HDL_TAP"TRUE";
"B \NAC \NWC"3;
"S \NAC"
BN"6"159;
%"TAP"
"1","(-7650,5025)","2","mstr_standard","I87";
;
CDS_LIB"mstr_standard"
BODY_TYPE"PLUMBING"
HDL_TAP"TRUE";
"B \NAC \NWC"2;
"S \NAC"
BN"0"172;
%"TAP"
"1","(-7650,5075)","2","mstr_standard","I88";
;
CDS_LIB"mstr_standard"
BODY_TYPE"PLUMBING"
HDL_TAP"TRUE";
"B \NAC \NWC"2;
"S \NAC"
BN"1"170;
%"TAP"
"1","(-7650,5125)","2","mstr_standard","I89";
;
CDS_LIB"mstr_standard"
BODY_TYPE"PLUMBING"
HDL_TAP"TRUE";
"B \NAC \NWC"2;
"S \NAC"
BN"2"168;
%"VCC_CORE"
"1","(-8450,3375)","0","mstr_symbols","I9";
;
HDL_POWER"P3V3_STBY"
CDS_LIB"mstr_symbols"
VOLTAGE"3.3"
ROOM"PVCCINFAON_CPU0_CTRL";
"A"19;
%"TAP"
"1","(-7650,5175)","2","mstr_standard","I90";
;
CDS_LIB"mstr_standard"
BODY_TYPE"PLUMBING"
HDL_TAP"TRUE";
"B \NAC \NWC"2;
"S \NAC"
BN"3"166;
%"TAP"
"1","(-7650,5225)","2","mstr_standard","I91";
;
CDS_LIB"mstr_standard"
BODY_TYPE"PLUMBING"
HDL_TAP"TRUE";
"B \NAC \NWC"2;
"S \NAC"
BN"4"164;
%"TAP"
"1","(-7650,5275)","2","mstr_standard","I92";
;
CDS_LIB"mstr_standard"
BODY_TYPE"PLUMBING"
HDL_TAP"TRUE";
"B \NAC \NWC"2;
"S \NAC"
BN"5"162;
%"TAP"
"1","(-7650,5325)","2","mstr_standard","I93";
;
CDS_LIB"mstr_standard"
BODY_TYPE"PLUMBING"
HDL_TAP"TRUE";
"B \NAC \NWC"2;
"S \NAC"
BN"6"160;
%"TAP"
"1","(-5950,3775)","0","mstr_standard","I94";
;
CDS_LIB"mstr_standard"
BODY_TYPE"PLUMBING"
HDL_TAP"TRUE";
"B \NAC \NWC"5;
"S \NAC"
BN"0"111;
%"TAP"
"1","(-5950,3875)","0","mstr_standard","I95";
;
CDS_LIB"mstr_standard"
BODY_TYPE"PLUMBING"
HDL_TAP"TRUE";
"B \NAC \NWC"5;
"S \NAC"
BN"2"113;
%"TAP"
"1","(-5950,3825)","0","mstr_standard","I96";
;
CDS_LIB"mstr_standard"
BODY_TYPE"PLUMBING"
HDL_TAP"TRUE";
"B \NAC \NWC"5;
"S \NAC"
BN"1"112;
%"TAP"
"1","(-5950,3925)","0","mstr_standard","I97";
;
CDS_LIB"mstr_standard"
BODY_TYPE"PLUMBING"
HDL_TAP"TRUE";
"B \NAC \NWC"5;
"S \NAC"
BN"3"114;
%"TAP"
"1","(-5950,3975)","0","mstr_standard","I98";
;
CDS_LIB"mstr_standard"
BODY_TYPE"PLUMBING"
HDL_TAP"TRUE";
"B \NAC \NWC"5;
"S \NAC"
BN"4"115;
%"TAP"
"1","(-5950,4025)","0","mstr_standard","I99";
;
CDS_LIB"mstr_standard"
BODY_TYPE"PLUMBING"
HDL_TAP"TRUE";
"B \NAC \NWC"5;
"S \NAC"
BN"5"116;
END.
